(kicad_pcb
	(version 20260206)
	(generator "pcbnew")
	(generator_version "10.0")
	(general
		(thickness 1.21888)
		(legacy_teardrops no)
	)
	(paper "A4")
	(title_block
		(title "timecard-beta-v1 — TimeCard-DC-V1.PcbDoc")
		(comment 1 "Time Appliance Project (Time Card) / footprints 50-59 of 120")
	)
	(layers
		(0 "F.Cu" signal "TOP")
		(4 "In1.Cu" signal "SGND")
		(6 "In2.Cu" signal "IN1")
		(8 "In3.Cu" signal "IN2")
		(10 "In4.Cu" signal "SGND1")
		(2 "B.Cu" signal "BOTTOM")
		(9 "F.Adhes" user "F.Adhesive")
		(11 "B.Adhes" user "B.Adhesive")
		(13 "F.Paste" user "Top Paste")
		(15 "B.Paste" user "Bottom Paste")
		(5 "F.SilkS" user "Top Overlay")
		(7 "B.SilkS" user "Bottom Overlay")
		(1 "F.Mask" user "Top Solder")
		(3 "B.Mask" user "Bottom Solder")
		(17 "Dwgs.User" user "User.Drawings")
		(19 "Cmts.User" user "User.Comments")
		(21 "Eco1.User" user "User.Eco1")
		(23 "Eco2.User" user "User.Eco2")
		(25 "Edge.Cuts" user)
		(27 "Margin" user)
		(31 "F.CrtYd" user "Top Courtyard")
		(29 "B.CrtYd" user "Bottom Courtyard")
		(35 "F.Fab" user "Top Component Center")
		(33 "B.Fab" user "Bottom Component Center")
	)
	(footprint "Vault:CAPC1608X87X45ML20T05"
		(layer "F.Cu")
		(at 219.588595 94.3786 180)
		(property "Reference" "C11"
			(at 4.1 0.606655 0)
			(unlocked yes)
			(layer "F.SilkS")
			(effects
				(font
					(size 0.762 0.762)
					(thickness 0.2286)
				)
				(justify left bottom)
			)
		)
		(property "Value" "0.1uF"
			(at -11.3919 -1.69799 0)
			(unlocked yes)
			(layer "F.SilkS")
			(hide yes)
			(effects
				(font
					(size 1.524 1.524)
					(thickness 0.254)
				)
				(justify left bottom)
			)
		)
		(sheetname "POWER")
		(sheetfile "POWER.kicad_sch")
		(duplicate_pad_numbers_are_jumpers no)
		(pad "1" smd rect
			(at -0.7 0 270)
			(size 1.1 1.05)
			(layers "F.Cu" "F.Mask" "F.Paste")
			(net "GND")
		)
		(pad "2" smd rect
			(at 0.7 0 270)
			(size 1.1 1.05)
			(layers "F.Cu" "F.Mask" "F.Paste")
			(net "+3.3V")
		)
	)
	(footprint "Resistors:RESC2012X50N"
		(layer "F.Cu")
		(at 104.488595 65.3286 90)
		(property "Reference" "R20"
			(at -1.25 -6.406655 90)
			(unlocked yes)
			(layer "F.SilkS")
			(effects
				(font
					(size 0.762 0.762)
					(thickness 0.2286)
				)
				(justify left bottom)
			)
		)
		(property "Value" "CRCW080533R0FKEA"
			(at -3.52679 -1.5875 0)
			(unlocked yes)
			(layer "F.SilkS")
			(hide yes)
			(effects
				(font
					(size 1.524 1.524)
					(thickness 0.254)
				)
				(justify left bottom)
			)
		)
		(sheetname "PCIe_JTAG")
		(sheetfile "PCIe_JTAG.kicad_sch")
		(duplicate_pad_numbers_are_jumpers no)
		(fp_line
			(start 0 -0.762)
			(end 0 0.762)
			(stroke
				(width 0.1524)
				(type solid)
			)
			(layer "F.SilkS")
		)
		(pad "1" smd rect
			(at -1 0 180)
			(size 1.45 0.95)
			(layers "F.Cu" "F.Mask" "F.Paste")
			(net "FPGA_TMS")
		)
		(pad "2" smd rect
			(at 1 0 180)
			(size 1.45 0.95)
			(layers "F.Cu" "F.Mask" "F.Paste")
			(net "NetR20_2")
		)
	)
	(footprint "Vault:CAPC1608X87X45ML20T05"
		(layer "F.Cu")
		(at 191.238595 86.3286)
		(property "Reference" "C23"
			(at -2.7714 0.026931 0)
			(unlocked yes)
			(layer "F.SilkS")
			(effects
				(font
					(size 0.762 0.762)
					(thickness 0.2286)
				)
			)
		)
		(property "Value" "0.1uF"
			(at 2.09443 2.657602 0)
			(unlocked yes)
			(layer "F.SilkS")
			(hide yes)
			(effects
				(font
					(size 1.524 1.524)
					(thickness 0.254)
				)
			)
		)
		(sheetname "MAC")
		(sheetfile "MAC.kicad_sch")
		(duplicate_pad_numbers_are_jumpers no)
		(pad "1" smd rect
			(at -0.7 0 90)
			(size 1.1 1.05)
			(layers "F.Cu" "F.Mask" "F.Paste")
			(net "GND")
		)
		(pad "2" smd rect
			(at 0.7 0 90)
			(size 1.1 1.05)
			(layers "F.Cu" "F.Mask" "F.Paste")
			(net "+3.3V")
		)
	)
	(footprint "Vault:FP-318BQ-MFG"
		(layer "F.Cu")
		(at 86.488595 97.0786 180)
		(property "Reference" "U6"
			(at -1.228605 2.723069 0)
			(unlocked yes)
			(layer "F.SilkS")
			(effects
				(font
					(size 0.762 0.762)
					(thickness 0.2286)
				)
			)
		)
		(property "Value" "NC7SZ125M5"
			(at 5.03956 3.495802 180)
			(unlocked yes)
			(layer "F.SilkS")
			(hide yes)
			(effects
				(font
					(size 1.524 1.524)
					(thickness 0.254)
				)
			)
		)
		(sheetname "USER_IO")
		(sheetfile "USER_IO.kicad_sch")
		(duplicate_pad_numbers_are_jumpers no)
		(fp_line
			(start 0.825 -0.225)
			(end 0.825 0.225)
			(stroke
				(width 0.2)
				(type solid)
			)
			(layer "F.SilkS")
		)
		(fp_line
			(start 0.325 1.575)
			(end -0.325 1.575)
			(stroke
				(width 0.2)
				(type solid)
			)
			(layer "F.SilkS")
		)
		(fp_line
			(start 0.325 -1.575)
			(end -0.325 -1.575)
			(stroke
				(width 0.2)
				(type solid)
			)
			(layer "F.SilkS")
		)
		(fp_circle
			(center -2.45 -0.95)
			(end -2.45 -0.825)
			(stroke
				(width 0.25)
				(type solid)
			)
			(fill no)
			(layer "F.SilkS")
		)
		(fp_line
			(start 1.8 1.825)
			(end -1.8 1.825)
			(stroke
				(width 0.2)
				(type solid)
			)
			(layer "F.CrtYd")
		)
		(fp_line
			(start 1.8 -1.825)
			(end 1.8 1.825)
			(stroke
				(width 0.2)
				(type solid)
			)
			(layer "F.CrtYd")
		)
		(fp_line
			(start 1.8 -1.825)
			(end -1.8 -1.825)
			(stroke
				(width 0.2)
				(type solid)
			)
			(layer "F.CrtYd")
		)
		(fp_line
			(start -1.8 -1.825)
			(end -1.8 1.825)
			(stroke
				(width 0.2)
				(type solid)
			)
			(layer "F.CrtYd")
		)
		(fp_line
			(start 1.8 1.825)
			(end -1.8 1.825)
			(stroke
				(width 0.2)
				(type solid)
			)
			(layer "F.Fab")
		)
		(fp_line
			(start 1.8 -1.825)
			(end 1.8 1.825)
			(stroke
				(width 0.2)
				(type solid)
			)
			(layer "F.Fab")
		)
		(fp_line
			(start 1.8 -1.825)
			(end -1.8 -1.825)
			(stroke
				(width 0.2)
				(type solid)
			)
			(layer "F.Fab")
		)
		(fp_line
			(start 0.5 0)
			(end -0.5 0)
			(stroke
				(width 0.1)
				(type solid)
			)
			(layer "F.Fab")
		)
		(fp_line
			(start 0 -0.5)
			(end 0 0.5)
			(stroke
				(width 0.1)
				(type solid)
			)
			(layer "F.Fab")
		)
		(fp_line
			(start -1.8 -1.825)
			(end -1.8 1.825)
			(stroke
				(width 0.2)
				(type solid)
			)
			(layer "F.Fab")
		)
		(fp_text user "${REFERENCE}"
			(at 0 0.28494 180)
			(unlocked yes)
			(layer "F.Fab")
			(effects
				(font
					(face "Arial")
					(size 0.63 0.63)
					(thickness 0.1)
				)
				(justify left bottom)
			)
		)
		(pad "1" smd rect
			(at -1.2 -0.95 180)
			(size 1 0.7)
			(layers "F.Cu" "F.Mask" "F.Paste")
			(net "GND")
			(solder_mask_margin 0)
			(solder_paste_margin 0)
		)
		(pad "2" smd rect
			(at -1.2 0 180)
			(size 1 0.7)
			(layers "F.Cu" "F.Mask" "F.Paste")
			(net "ANT1")
			(solder_mask_margin 0)
			(solder_paste_margin 0)
		)
		(pad "3" smd rect
			(at -1.2 0.95 180)
			(size 1 0.7)
			(layers "F.Cu" "F.Mask" "F.Paste")
			(net "GND")
			(solder_mask_margin 0)
			(solder_paste_margin 0)
		)
		(pad "4" smd rect
			(at 1.2 0.95 180)
			(size 1 0.7)
			(layers "F.Cu" "F.Mask" "F.Paste")
			(net "NetR14_1")
			(solder_mask_margin 0)
			(solder_paste_margin 0)
		)
		(pad "5" smd rect
			(at 1.2 -0.95 180)
			(size 1 0.7)
			(layers "F.Cu" "F.Mask" "F.Paste")
			(net "+3.3V")
			(solder_mask_margin 0)
			(solder_paste_margin 0)
		)
	)
	(footprint "Vault:FP-5TS1-IPC_C"
		(layer "F.Cu")
		(at 134.238595 89.0786 -90)
		(property "Reference" "U7"
			(at -2.723069 0.771395 0)
			(unlocked yes)
			(layer "F.SilkS")
			(effects
				(font
					(size 0.762 0.762)
					(thickness 0.2286)
				)
			)
		)
		(property "Value" "AT24MAC402-STUM-T"
			(at 10.752795 3.216402 270)
			(unlocked yes)
			(layer "F.SilkS")
			(hide yes)
			(effects
				(font
					(size 1.524 1.524)
					(thickness 0.254)
				)
			)
		)
		(sheetname "GPS_IMU_SENSORS")
		(sheetfile "GPS_IMU_SENSORS.kicad_sch")
		(duplicate_pad_numbers_are_jumpers no)
		(fp_line
			(start 0.17208 1.45)
			(end -0.17207 1.45)
			(stroke
				(width 0.2)
				(type solid)
			)
			(layer "F.SilkS")
		)
		(fp_line
			(start 0.8 0.30893)
			(end 0.8 -0.30894)
			(stroke
				(width 0.2)
				(type solid)
			)
			(layer "F.SilkS")
		)
		(fp_line
			(start 0.17208 -1.45)
			(end -0.17207 -1.45)
			(stroke
				(width 0.2)
				(type solid)
			)
			(layer "F.SilkS")
		)
		(fp_circle
			(center -2.21035 -0.95)
			(end -2.33535 -0.95)
			(stroke
				(width 0.25)
				(type solid)
			)
			(fill no)
			(layer "F.SilkS")
		)
		(fp_line
			(start -1.68536 1.55)
			(end -1.68536 -1.55)
			(stroke
				(width 0.2)
				(type solid)
			)
			(layer "F.CrtYd")
		)
		(fp_line
			(start 1.68536 1.55)
			(end -1.68536 1.55)
			(stroke
				(width 0.2)
				(type solid)
			)
			(layer "F.CrtYd")
		)
		(fp_line
			(start 1.68536 1.55)
			(end 1.68536 -1.55)
			(stroke
				(width 0.2)
				(type solid)
			)
			(layer "F.CrtYd")
		)
		(fp_line
			(start 1.68536 -1.55)
			(end -1.68536 -1.55)
			(stroke
				(width 0.2)
				(type solid)
			)
			(layer "F.CrtYd")
		)
		(fp_line
			(start -1.68536 1.55)
			(end -1.68536 -1.55)
			(stroke
				(width 0.2)
				(type solid)
			)
			(layer "F.Fab")
		)
		(fp_line
			(start 1.68536 1.55)
			(end -1.68536 1.55)
			(stroke
				(width 0.2)
				(type solid)
			)
			(layer "F.Fab")
		)
		(fp_line
			(start 1.68536 1.55)
			(end 1.68536 -1.55)
			(stroke
				(width 0.2)
				(type solid)
			)
			(layer "F.Fab")
		)
		(fp_line
			(start 0 0.5)
			(end 0 -0.5)
			(stroke
				(width 0.1)
				(type solid)
			)
			(layer "F.Fab")
		)
		(fp_line
			(start 0.5 0)
			(end -0.5 0)
			(stroke
				(width 0.1)
				(type solid)
			)
			(layer "F.Fab")
		)
		(fp_line
			(start 1.68536 -1.55)
			(end -1.68536 -1.55)
			(stroke
				(width 0.2)
				(type solid)
			)
			(layer "F.Fab")
		)
		(fp_text user "${REFERENCE}"
			(at 0.00001 0.28494 270)
			(unlocked yes)
			(layer "F.Fab")
			(effects
				(font
					(face "Arial")
					(size 0.63 0.63)
					(thickness 0.1)
				)
				(justify left bottom)
			)
		)
		(pad "1" smd rect
			(at -1.06621 -0.95 270)
			(size 1.03828 0.53213)
			(layers "F.Cu" "F.Mask" "F.Paste")
			(net "SCL")
			(solder_mask_margin 0)
			(solder_paste_margin 0)
		)
		(pad "2" smd roundrect
			(at -1.06621 0 270)
			(size 1.03828 0.53213)
			(layers "F.Cu" "F.Mask" "F.Paste")
			(roundrect_rratio 0.5)
			(net "GND")
			(solder_mask_margin 0)
			(solder_paste_margin 0)
		)
		(pad "3" smd roundrect
			(at -1.06621 0.95 270)
			(size 1.03828 0.53213)
			(layers "F.Cu" "F.Mask" "F.Paste")
			(roundrect_rratio 0.5)
			(net "SDA")
			(solder_mask_margin 0)
			(solder_paste_margin 0)
		)
		(pad "4" smd roundrect
			(at 1.06621 0.95 270)
			(size 1.03828 0.53213)
			(layers "F.Cu" "F.Mask" "F.Paste")
			(roundrect_rratio 0.5)
			(net "+3.3V")
			(solder_mask_margin 0)
			(solder_paste_margin 0)
		)
		(pad "5" smd roundrect
			(at 1.06621 -0.95 270)
			(size 1.03828 0.53213)
			(layers "F.Cu" "F.Mask" "F.Paste")
			(roundrect_rratio 0.5)
			(net "EXT_EEPROM_WP")
			(solder_mask_margin 0)
			(solder_paste_margin 0)
		)
	)
	(footprint "Vault:CAPC1608X90X35NL10T15"
		(layer "F.Cu")
		(at 212.535595 100.6076 90)
		(property "Reference" "C22"
			(at 1.479 0.396345 90)
			(unlocked yes)
			(layer "F.SilkS")
			(effects
				(font
					(size 0.762 0.762)
					(thickness 0.2286)
				)
				(justify left bottom)
			)
		)
		(property "Value" "0.033uF"
			(at 8.20801 25.6159 0)
			(unlocked yes)
			(layer "F.SilkS")
			(hide yes)
			(effects
				(font
					(size 1.524 1.524)
					(thickness 0.254)
				)
				(justify left bottom)
			)
		)
		(sheetname "POWER")
		(sheetfile "POWER.kicad_sch")
		(duplicate_pad_numbers_are_jumpers no)
		(pad "1" smd rect
			(at -0.675 0 180)
			(size 0.95 0.85)
			(layers "F.Cu" "F.Mask" "F.Paste")
			(net "NetC22_1")
		)
		(pad "2" smd rect
			(at 0.675 0 180)
			(size 0.95 0.85)
			(layers "F.Cu" "F.Mask" "F.Paste")
			(net "NetC22_2")
		)
	)
	(footprint "Capacitors:CAPC2012X14N"
		(layer "F.Cu")
		(at 109.788595 143.6786 90)
		(property "Reference" "C1"
			(at 2.1 -0.456655 90)
			(unlocked yes)
			(layer "F.SilkS")
			(effects
				(font
					(size 0.762 0.762)
					(thickness 0.2286)
				)
				(justify left bottom)
			)
		)
		(property "Value" "CAP_0805_10UF_25V"
			(at -3.52679 -1.5875 0)
			(unlocked yes)
			(layer "F.SilkS")
			(hide yes)
			(effects
				(font
					(size 1.524 1.524)
					(thickness 0.254)
				)
				(justify left bottom)
			)
		)
		(sheetname "POWER")
		(sheetfile "POWER.kicad_sch")
		(duplicate_pad_numbers_are_jumpers no)
		(fp_line
			(start -0.762 -0.9652)
			(end 0.762 -0.9652)
			(stroke
				(width 0.1524)
				(type solid)
			)
			(layer "F.SilkS")
		)
		(fp_line
			(start -0.762 0.9652)
			(end 0.762 0.9652)
			(stroke
				(width 0.1524)
				(type solid)
			)
			(layer "F.SilkS")
		)
		(pad "1" smd rect
			(at -0.9 0 180)
			(size 1.45 1.15)
			(layers "F.Cu" "F.Mask" "F.Paste")
			(net "+12V")
		)
		(pad "2" smd rect
			(at 0.9 0 180)
			(size 1.45 1.15)
			(layers "F.Cu" "F.Mask" "F.Paste")
			(net "GND")
		)
	)
	(footprint "Vault:FP-318BQ-MFG"
		(layer "F.Cu")
		(at 86.188605 136.0286)
		(property "Reference" "U12"
			(at -0.97861 2.723069 180)
			(unlocked yes)
			(layer "F.SilkS")
			(effects
				(font
					(size 0.762 0.762)
					(thickness 0.2286)
				)
			)
		)
		(property "Value" "NC7SZ125M5"
			(at 5.03956 3.495802 0)
			(unlocked yes)
			(layer "F.SilkS")
			(hide yes)
			(effects
				(font
					(size 1.524 1.524)
					(thickness 0.254)
				)
			)
		)
		(sheetname "USER_IO")
		(sheetfile "USER_IO.kicad_sch")
		(duplicate_pad_numbers_are_jumpers no)
		(fp_line
			(start -0.325 -1.575)
			(end 0.325 -1.575)
			(stroke
				(width 0.2)
				(type solid)
			)
			(layer "F.SilkS")
		)
		(fp_line
			(start -0.325 1.575)
			(end 0.325 1.575)
			(stroke
				(width 0.2)
				(type solid)
			)
			(layer "F.SilkS")
		)
		(fp_line
			(start 0.825 0.225)
			(end 0.825 -0.225)
			(stroke
				(width 0.2)
				(type solid)
			)
			(layer "F.SilkS")
		)
		(fp_circle
			(center -2.45 -0.95)
			(end -2.45 -1.075)
			(stroke
				(width 0.25)
				(type solid)
			)
			(fill no)
			(layer "F.SilkS")
		)
		(fp_line
			(start -1.8 -1.825)
			(end 1.8 -1.825)
			(stroke
				(width 0.2)
				(type solid)
			)
			(layer "F.CrtYd")
		)
		(fp_line
			(start -1.8 1.825)
			(end -1.8 -1.825)
			(stroke
				(width 0.2)
				(type solid)
			)
			(layer "F.CrtYd")
		)
		(fp_line
			(start -1.8 1.825)
			(end 1.8 1.825)
			(stroke
				(width 0.2)
				(type solid)
			)
			(layer "F.CrtYd")
		)
		(fp_line
			(start 1.8 1.825)
			(end 1.8 -1.825)
			(stroke
				(width 0.2)
				(type solid)
			)
			(layer "F.CrtYd")
		)
		(fp_line
			(start -1.8 -1.825)
			(end 1.8 -1.825)
			(stroke
				(width 0.2)
				(type solid)
			)
			(layer "F.Fab")
		)
		(fp_line
			(start -1.8 1.825)
			(end -1.8 -1.825)
			(stroke
				(width 0.2)
				(type solid)
			)
			(layer "F.Fab")
		)
		(fp_line
			(start -1.8 1.825)
			(end 1.8 1.825)
			(stroke
				(width 0.2)
				(type solid)
			)
			(layer "F.Fab")
		)
		(fp_line
			(start -0.5 0)
			(end 0.5 0)
			(stroke
				(width 0.1)
				(type solid)
			)
			(layer "F.Fab")
		)
		(fp_line
			(start 0 0.5)
			(end 0 -0.5)
			(stroke
				(width 0.1)
				(type solid)
			)
			(layer "F.Fab")
		)
		(fp_line
			(start 1.8 1.825)
			(end 1.8 -1.825)
			(stroke
				(width 0.2)
				(type solid)
			)
			(layer "F.Fab")
		)
		(fp_text user "${REFERENCE}"
			(at 0 0.28494 360)
			(unlocked yes)
			(layer "F.Fab")
			(effects
				(font
					(face "Arial")
					(size 0.63 0.63)
					(thickness 0.1)
				)
				(justify left bottom)
			)
		)
		(pad "1" smd rect
			(at -1.2 -0.95)
			(size 1 0.7)
			(layers "F.Cu" "F.Mask" "F.Paste")
			(net "GND")
			(solder_mask_margin 0)
			(solder_paste_margin 0)
		)
		(pad "2" smd rect
			(at -1.2 0)
			(size 1 0.7)
			(layers "F.Cu" "F.Mask" "F.Paste")
			(net "NetR25_1")
			(solder_mask_margin 0)
			(solder_paste_margin 0)
		)
		(pad "3" smd rect
			(at -1.2 0.95)
			(size 1 0.7)
			(layers "F.Cu" "F.Mask" "F.Paste")
			(net "GND")
			(solder_mask_margin 0)
			(solder_paste_margin 0)
		)
		(pad "4" smd rect
			(at 1.2 0.95)
			(size 1 0.7)
			(layers "F.Cu" "F.Mask" "F.Paste")
			(net "ANT4")
			(solder_mask_margin 0)
			(solder_paste_margin 0)
		)
		(pad "5" smd rect
			(at 1.2 -0.95)
			(size 1 0.7)
			(layers "F.Cu" "F.Mask" "F.Paste")
			(net "+3.3V")
			(solder_mask_margin 0)
			(solder_paste_margin 0)
		)
	)
	(footprint "Vault:CAPC1608X87X45ML20T05"
		(layer "F.Cu")
		(at 219.588595 96.1786 180)
		(property "Reference" "C10"
			(at 4.1 1.006655 0)
			(unlocked yes)
			(layer "F.SilkS")
			(effects
				(font
					(size 0.762 0.762)
					(thickness 0.2286)
				)
				(justify left bottom)
			)
		)
		(property "Value" "0.1uF"
			(at -9.9949 -0.30099 0)
			(unlocked yes)
			(layer "F.SilkS")
			(hide yes)
			(effects
				(font
					(size 1.524 1.524)
					(thickness 0.254)
				)
				(justify left bottom)
			)
		)
		(sheetname "POWER")
		(sheetfile "POWER.kicad_sch")
		(duplicate_pad_numbers_are_jumpers no)
		(pad "1" smd rect
			(at -0.7 0 270)
			(size 1.1 1.05)
			(layers "F.Cu" "F.Mask" "F.Paste")
			(net "GND")
		)
		(pad "2" smd rect
			(at 0.7 0 270)
			(size 1.1 1.05)
			(layers "F.Cu" "F.Mask" "F.Paste")
			(net "+3.3V")
		)
	)
	(footprint "Vault:CAPC1608X87X45ML20T05"
		(layer "F.Cu")
		(at 140.288595 92.0786 180)
		(property "Reference" "C32"
			(at 3.0714 -0.026931 0)
			(unlocked yes)
			(layer "F.SilkS")
			(effects
				(font
					(size 0.762 0.762)
					(thickness 0.2286)
				)
			)
		)
		(property "Value" "0.1uF"
			(at 2.09443 2.657602 180)
			(unlocked yes)
			(layer "F.SilkS")
			(hide yes)
			(effects
				(font
					(size 1.524 1.524)
					(thickness 0.254)
				)
			)
		)
		(sheetname "GPS_IMU_SENSORS")
		(sheetfile "GPS_IMU_SENSORS.kicad_sch")
		(duplicate_pad_numbers_are_jumpers no)
		(pad "1" smd rect
			(at -0.7 0 270)
			(size 1.1 1.05)
			(layers "F.Cu" "F.Mask" "F.Paste")
			(net "GND")
		)
		(pad "2" smd rect
			(at 0.7 0 270)
			(size 1.1 1.05)
			(layers "F.Cu" "F.Mask" "F.Paste")
			(net "+3.3V")
		)
	)
)
